(kicad_pcb
	(version 20221018)
	(generator pcbnew)
	(general
    (thickness 1.656)
  )
	(paper "A4")
	(title_block
    (title "SDI-MIPI Bridge")
    (date "2023-08-09")
    (rev "1.3.4")
    (company "Antmicro")
		(comment 9 "footprints 64-69 of 190")
	)
	(layers
    (0 "F.Cu" signal)
    (1 "In1.Cu" power)
    (2 "In2.Cu" power)
    (3 "In3.Cu" signal)
    (4 "In4.Cu" signal)
    (31 "B.Cu" signal)
    (32 "B.Adhes" user "B.Adhesive")
    (33 "F.Adhes" user "F.Adhesive")
    (34 "B.Paste" user)
    (35 "F.Paste" user)
    (36 "B.SilkS" user "B.Silkscreen")
    (37 "F.SilkS" user "F.Silkscreen")
    (38 "B.Mask" user)
    (39 "F.Mask" user)
    (40 "Dwgs.User" user "User.Drawings")
    (41 "Cmts.User" user "User.Comments")
    (42 "Eco1.User" user "User.Eco1")
    (43 "Eco2.User" user "User.Eco2")
    (44 "Edge.Cuts" user)
    (45 "Margin" user)
    (46 "B.CrtYd" user "B.Courtyard")
    (47 "F.CrtYd" user "F.Courtyard")
    (48 "B.Fab" user)
    (49 "F.Fab" user)
  )
	(footprint "sdi-mipi-bridge-footprints:PinHeader_2x5_P1.27mm_Drill0.65mm" (layer "F.Cu")
    (at 121.889 133.95 180)
    (descr "Through hole straight pin header, 2x5, 1.27mm pitch, double rows")
    (tags "Through hole pin header THT 2x5 1.27mm double row")
    (property "Author" "Antmicro")
    (property "License" "Apache-2.0")
    (property "MPN" "2199SB-10G-301523")
    (property "Manufacturer" "Multicomp Pro")
    (property "Sheetfile" "sdi-mipi-bridge.kicad_sch")
    (property "Sheetname" "")
    (property "ki_description" "Pin Header, Board-to-Board, 1.27 mm, 2 Rows, 10 Contacts, Through Hole Straight, 2199SB")
    (property "ki_keywords" "PINSTRIP, HEADER, THT")
    (attr through_hole)
    (fp_text reference "J4" (at 0 -2.9 180) (layer "F.SilkS")
        (effects (font (size 0.7 0.7) (thickness 0.15)) (justify left bottom))
    )
    (fp_text value "PinHeader_2x5_P1.27mm_Vertical" (at 0 2.3 180) (layer "F.Fab")
        (effects (font (size 0.7 0.7) (thickness 0.15)) (justify left bottom))
    )
    (fp_text user "${REFERENCE}" (at -1.135 9.999 180) (layer "F.Fab") hide
        (effects (font (size 0.7 0.7) (thickness 0.15)) (justify left bottom))
    )
    (fp_text user "Author: Antmicro" (at -1.135 12.399 180) (layer "F.Fab") hide
        (effects (font (size 0.7 0.7) (thickness 0.15)) (justify left bottom))
    )
    (fp_text user "License: Apache-2.0" (at -1.135 11.198 180) (layer "F.Fab") hide
        (effects (font (size 0.7 0.7) (thickness 0.15)) (justify left bottom))
    )
    (fp_line (start -0.702 -2.403) (end -0.702 -1.901)
      (stroke (width 0.15) (type solid)) (layer "F.SilkS"))
    (fp_line (start -0.702 -2.403) (end -0.202 -2.403)
      (stroke (width 0.15) (type solid)) (layer "F.SilkS"))
    (fp_line (start 5.797 -2.4) (end 5.297 -2.4)
      (stroke (width 0.15) (type solid)) (layer "F.SilkS"))
    (fp_line (start 5.797 -2.4) (end 5.797 -1.899)
      (stroke (width 0.15) (type solid)) (layer "F.SilkS"))
    (fp_line (start 5.797 1.1) (end 5.297 1.1)
      (stroke (width 0.15) (type solid)) (layer "F.SilkS"))
    (fp_line (start 5.797 1.1) (end 5.797 0.598)
      (stroke (width 0.15) (type solid)) (layer "F.SilkS"))
    (fp_poly
      (pts
        (xy -0.702 0.598)
        (xy -0.702 1.1)
        (xy -0.202 1.1)
      )

      (stroke (width 0.15) (type solid)) (fill solid) (layer "F.SilkS"))
    (fp_rect (start -0.9 -2.6) (end 6 1.3)
      (stroke (width 0.05) (type solid)) (fill none) (layer "F.CrtYd"))
    (fp_line (start -0.635 -2.339) (end 5.712 -2.339)
      (stroke (width 0.15) (type solid)) (layer "F.Fab"))
    (fp_line (start -0.635 0.216) (end -0.635 -2.339)
      (stroke (width 0.15) (type solid)) (layer "F.Fab"))
    (fp_line (start 0.214 1.07) (end -0.635 0.216)
      (stroke (width 0.15) (type solid)) (layer "F.Fab"))
    (fp_line (start 5.712 -2.339) (end 5.712 1.07)
      (stroke (width 0.15) (type solid)) (layer "F.Fab"))
    (fp_line (start 5.712 1.07) (end 0.214 1.07)
      (stroke (width 0.15) (type solid)) (layer "F.Fab"))
    (pad "1" thru_hole rect (at 0 0 270) (size 1 1) (drill 0.65) (layers "*.Cu" "*.Mask")
      (net 28 "/AUDIO_SERIAL_BIT_CLK") (pintype "passive"))
    (pad "2" thru_hole oval (at 0 -1.27 270) (size 1 1) (drill 0.65) (layers "*.Cu" "*.Mask")
      (net 28 "/AUDIO_SERIAL_BIT_CLK") (pintype "passive"))
    (pad "3" thru_hole oval (at 1.269 0 270) (size 1 1) (drill 0.65) (layers "*.Cu" "*.Mask")
      (net 60 "/AUDIO_WORD_CLK") (pintype "passive"))
    (pad "4" thru_hole oval (at 1.269 -1.27 270) (size 1 1) (drill 0.65) (layers "*.Cu" "*.Mask")
      (net 60 "/AUDIO_WORD_CLK") (pintype "passive"))
    (pad "5" thru_hole oval (at 2.539 0 270) (size 1 1) (drill 0.65) (layers "*.Cu" "*.Mask")
      (net 52 "/AUDIO_OUTPUT_CH1_2") (pintype "passive"))
    (pad "6" thru_hole oval (at 2.539 -1.27 270) (size 1 1) (drill 0.65) (layers "*.Cu" "*.Mask")
      (net 50 "/AUDIO_OUTPUT_CH5_6") (pintype "passive"))
    (pad "7" thru_hole oval (at 3.809 0 270) (size 1 1) (drill 0.65) (layers "*.Cu" "*.Mask")
      (net 51 "/AUDIO_OUTPUT_CH3_4") (pintype "passive"))
    (pad "8" thru_hole oval (at 3.809 -1.27 270) (size 1 1) (drill 0.65) (layers "*.Cu" "*.Mask")
      (net 49 "/AUDIO_OUTPUT_CH7_8") (pintype "passive"))
    (pad "9" thru_hole oval (at 5.076 0 270) (size 1 1) (drill 0.65) (layers "*.Cu" "*.Mask")
      (net 3 "GNDA") (pintype "passive"))
    (pad "10" thru_hole oval (at 5.076 -1.27 270) (size 1 1) (drill 0.65) (layers "*.Cu" "*.Mask")
      (net 26 "/AUDIO_MASTER_CLK") (pintype "passive"))
  )
	(footprint "sdi-mipi-bridge-footprints:R_0402_1005Metric" (layer "F.Cu")
    (at 153.4 133 -90)
    (descr "Resistor SMD 0402")
    (tags "resistor SMD 0402")
    (property "Author" "Antmicro")
    (property "Current" "1A")
    (property "License" "Apache-2.0")
    (property "MPN" "ERJ2GE0R00X")
    (property "Manufacturer" "Panasonic")
    (property "Sheetfile" "sdi-mipi-bridge.kicad_sch")
    (property "Sheetname" "")
    (property "Tolerance" "")
    (property "Val" "0R")
    (property "ki_description" "0R resistor in 0402 package with unspecified tolerance")
    (attr smd)
    (fp_text reference "R82" (at 1.05 -0.35 90) (layer "F.SilkS")
        (effects (font (size 0.65 0.65) (thickness 0.15)) (justify right bottom))
    )
    (fp_text value "R_0R_0402" (at 0 1.4 90) (layer "F.Fab") hide
        (effects (font (size 0.7 0.7) (thickness 0.15)) (justify right bottom))
    )
    (fp_text user "License: Apache-2.0" (at -0.95 5.169 90) (layer "F.Fab") hide
        (effects (font (size 0.7 0.7) (thickness 0.15)) (justify right bottom))
    )
    (fp_text user "${REFERENCE}" (at -0.95 3.168 90) (layer "F.Fab") hide
        (effects (font (size 0.7 0.7) (thickness 0.15)) (justify right bottom))
    )
    (fp_text user "Author: Antmicro" (at -0.95 4.169 90) (layer "F.Fab") hide
        (effects (font (size 0.7 0.7) (thickness 0.15)) (justify right bottom))
    )
    (fp_rect (start -0.93 -0.47) (end 0.93 0.47)
      (stroke (width 0.05) (type solid)) (fill none) (layer "F.CrtYd"))
    (fp_rect (start -0.5 -0.25) (end 0.5 0.25)
      (stroke (width 0.15) (type solid)) (fill none) (layer "F.Fab"))
    (pad "1" smd roundrect (at -0.485 0 270) (size 0.59 0.64) (layers "F.Cu" "F.Paste" "F.Mask") (roundrect_rratio 0.25)
      (net 105 "/USER_SW") (pintype "passive"))
    (pad "2" smd roundrect (at 0.485 0 270) (size 0.59 0.64) (layers "F.Cu" "F.Paste" "F.Mask") (roundrect_rratio 0.25)
      (net 125 "Net-(R82-Pad2)") (pintype "passive"))
  )
	(footprint "sdi-mipi-bridge-footprints:PinHeader_1x4_P1.27mm_Drill0.7mm" (layer "F.Cu")
    (at 117.35 102.25 90)
    (descr "http://cnctech.us/pdfs/3220-XX-0100-00.pdf")
    (property "Author" "Antmicro")
    (property "License" "Apache-2.0")
    (property "MPN" "MC-HVT1-S04-G")
    (property "Manufacturer" "Multicomp Pro")
    (property "Sheetfile" "sdi-mipi-bridge.kicad_sch")
    (property "Sheetname" "")
    (property "ki_description" "Pin Header, Board-to-Board, 1.27 mm, 1 Rows, 4 Contacts, Through Hole")
    (property "ki_keywords" "PINSTRIP, HEADER ")
    (attr through_hole)
    (fp_text reference "J5" (at 2.64 -4.08 90) (layer "F.SilkS")
        (effects (font (size 0.7 0.7) (thickness 0.15)) (justify left bottom))
    )
    (fp_text value "PinHeader_1x4_P1.27mm_Drill.7mm" (at 3.1 3.039 90) (layer "F.Fab") hide
        (effects (font (size 0.7 0.7) (thickness 0.15)) (justify left bottom))
    )
    (fp_text user "${REFERENCE}" (at -4.446 5.038 90) (layer "F.Fab") hide
        (effects (font (size 0.7 0.7) (thickness 0.15)) (justify left bottom))
    )
    (fp_text user "Author: Antmicro" (at -4.446 6.24 90) (layer "F.Fab") hide
        (effects (font (size 0.7 0.7) (thickness 0.15)) (justify left bottom))
    )
    (fp_text user "License: Apache-2.0" (at -4.446 7.44 90) (layer "F.Fab") hide
        (effects (font (size 0.7 0.7) (thickness 0.15)) (justify left bottom))
    )
    (fp_line (start -1.216 1.225) (end -1.216 0.723)
      (stroke (width 0.15) (type solid)) (layer "F.SilkS"))
    (fp_line (start -1.216 1.225) (end -0.715 1.225)
      (stroke (width 0.15) (type solid)) (layer "F.SilkS"))
    (fp_line (start 5.025 -1.226) (end 4.525 -1.226)
      (stroke (width 0.15) (type solid)) (layer "F.SilkS"))
    (fp_line (start 5.025 -1.226) (end 5.025 -0.725)
      (stroke (width 0.15) (type solid)) (layer "F.SilkS"))
    (fp_line (start 5.025 1.225) (end 4.525 1.225)
      (stroke (width 0.15) (type solid)) (layer "F.SilkS"))
    (fp_line (start 5.025 1.225) (end 5.025 0.723)
      (stroke (width 0.15) (type solid)) (layer "F.SilkS"))
    (fp_circle (center 0 -1.851) (end 0.05 -1.851)
      (stroke (width 0.15) (type solid)) (fill solid) (layer "F.SilkS"))
    (fp_poly
      (pts
        (xy -1.216 -0.725)
        (xy -1.216 -1.226)
        (xy -0.715 -1.226)
      )

      (stroke (width 0.15) (type solid)) (fill solid) (layer "F.SilkS"))
    (fp_rect (start 4.929 1.55) (end -1.15 -1.551)
      (stroke (width 0.05) (type solid)) (fill none) (layer "F.CrtYd"))
    (fp_line (start -1.101 1.1) (end 4.9 1.1)
      (stroke (width 0.15) (type solid)) (layer "F.Fab"))
    (fp_line (start -1.1 -0.5) (end -1.101 1.1)
      (stroke (width 0.15) (type solid)) (layer "F.Fab"))
    (fp_line (start -1.1 -0.5) (end -0.5 -1.1)
      (stroke (width 0.15) (type solid)) (layer "F.Fab"))
    (fp_line (start -0.5 -1.1) (end 4.9 -1.101)
      (stroke (width 0.15) (type solid)) (layer "F.Fab"))
    (fp_line (start 4.9 -1.101) (end 4.9 1.1)
      (stroke (width 0.15) (type solid)) (layer "F.Fab"))
    (pad "1" thru_hole circle (at 0 0 90) (size 1.1 1.1) (drill 0.7) (layers "*.Cu" "*.Mask")
      (net 6 "+3V3") (pintype "passive"))
    (pad "2" thru_hole circle (at 1.269 0 90) (size 1.1 1.1) (drill 0.7) (layers "*.Cu" "*.Mask")
      (net 62 "/SDA_GS") (pintype "passive"))
    (pad "3" thru_hole circle (at 2.539 0 90) (size 1.1 1.1) (drill 0.7) (layers "*.Cu" "*.Mask")
      (net 61 "/SCL_GS") (pintype "passive"))
    (pad "4" thru_hole circle (at 3.809 0 90) (size 1.1 1.1) (drill 0.7) (layers "*.Cu" "*.Mask")
      (net 1 "GNDREF") (pintype "passive"))
  )
	(footprint "sdi-mipi-bridge-footprints:R_0402_1005Metric" (layer "F.Cu")
    (at 140.5 129.75 90)
    (descr "Resistor SMD 0402")
    (tags "resistor SMD 0402")
    (property "Author" "Antmicro")
    (property "License" "Apache-2.0")
    (property "MPN" "CR0402-FX-1002GLF")
    (property "Manufacturer" "Bourns")
    (property "Sheetfile" "sdi-mipi-bridge.kicad_sch")
    (property "Sheetname" "")
    (property "Tolerance" "1%")
    (property "Val" "10k")
    (property "ki_description" "10k resistor in 0402 package with 1% tolerance")
    (attr smd)
    (fp_text reference "R76" (at -5.75 0.4 90) (layer "F.SilkS")
        (effects (font (size 0.65 0.65) (thickness 0.15)) (justify left bottom))
    )
    (fp_text value "R_10k_0402" (at 0 1.4 90) (layer "F.Fab") hide
        (effects (font (size 0.7 0.7) (thickness 0.15)) (justify left bottom))
    )
    (fp_text user "License: Apache-2.0" (at -0.95 5.169 90) (layer "F.Fab") hide
        (effects (font (size 0.7 0.7) (thickness 0.15)) (justify left bottom))
    )
    (fp_text user "Author: Antmicro" (at -0.95 4.169 90) (layer "F.Fab") hide
        (effects (font (size 0.7 0.7) (thickness 0.15)) (justify left bottom))
    )
    (fp_text user "${REFERENCE}" (at -0.95 3.168 90) (layer "F.Fab") hide
        (effects (font (size 0.7 0.7) (thickness 0.15)) (justify left bottom))
    )
    (fp_rect (start -0.93 -0.47) (end 0.93 0.47)
      (stroke (width 0.05) (type solid)) (fill none) (layer "F.CrtYd"))
    (fp_rect (start -0.5 -0.25) (end 0.5 0.25)
      (stroke (width 0.15) (type solid)) (fill none) (layer "F.Fab"))
    (pad "1" smd roundrect (at -0.485 0 90) (size 0.59 0.64) (layers "F.Cu" "F.Paste" "F.Mask") (roundrect_rratio 0.25)
      (net 53 "/Audio_EN_~{DIS}") (pintype "passive"))
    (pad "2" smd roundrect (at 0.485 0 90) (size 0.59 0.64) (layers "F.Cu" "F.Paste" "F.Mask") (roundrect_rratio 0.25)
      (net 76 "IO_VDD") (pintype "passive"))
  )
	(footprint "sdi-mipi-bridge-footprints:R_0402_1005Metric" (layer "F.Cu")
    (at 140.5 131.75 90)
    (descr "Resistor SMD 0402")
    (tags "resistor SMD 0402")
    (property "Author" "Antmicro")
    (property "DNP" "DNP")
    (property "License" "Apache-2.0")
    (property "MPN" "CR0402-FX-1002GLF")
    (property "Manufacturer" "Bourns")
    (property "Sheetfile" "sdi-mipi-bridge.kicad_sch")
    (property "Sheetname" "")
    (property "Tolerance" "1%")
    (property "Val" "10k")
    (property "ki_description" "10k resistor in 0402 package with 1% tolerance")
    (attr exclude_from_pos_files)
    (fp_text reference "R77" (at -5.75 0.4 90) (layer "F.SilkS")
        (effects (font (size 0.65 0.65) (thickness 0.15)) (justify left bottom))
    )
    (fp_text value "R_10k_0402" (at 0 1.4 90) (layer "F.Fab") hide
        (effects (font (size 0.7 0.7) (thickness 0.15)) (justify left bottom))
    )
    (fp_text user "License: Apache-2.0" (at -0.95 5.169 90) (layer "F.Fab") hide
        (effects (font (size 0.7 0.7) (thickness 0.15)) (justify left bottom))
    )
    (fp_text user "${REFERENCE}" (at -0.95 3.168 90) (layer "F.Fab") hide
        (effects (font (size 0.7 0.7) (thickness 0.15)) (justify left bottom))
    )
    (fp_text user "Author: Antmicro" (at -0.95 4.169 90) (layer "F.Fab") hide
        (effects (font (size 0.7 0.7) (thickness 0.15)) (justify left bottom))
    )
    (fp_rect (start -0.93 -0.47) (end 0.93 0.47)
      (stroke (width 0.05) (type solid)) (fill none) (layer "F.CrtYd"))
    (fp_rect (start -0.5 -0.25) (end 0.5 0.25)
      (stroke (width 0.15) (type solid)) (fill none) (layer "F.Fab"))
    (pad "1" smd roundrect (at -0.485 0 90) (size 0.59 0.64) (layers "F.Cu" "F.Paste" "F.Mask") (roundrect_rratio 0.25)
      (net 3 "GNDA") (pintype "passive"))
    (pad "2" smd roundrect (at 0.485 0 90) (size 0.59 0.64) (layers "F.Cu" "F.Paste" "F.Mask") (roundrect_rratio 0.25)
      (net 53 "/Audio_EN_~{DIS}") (pintype "passive"))
  )
	(footprint "sdi-mipi-bridge-footprints:PinHeader_2x5_P1.27mm_Drill0.65mm" (layer "F.Cu")
    (at 158.514 102.755499 90)
    (descr "Through hole straight pin header, 2x5, 1.27mm pitch, double rows")
    (tags "Through hole pin header THT 2x5 1.27mm double row")
    (property "Author" "Antmicro")
    (property "License" "Apache-2.0")
    (property "MPN" "2199SB-10G-301523")
    (property "Manufacturer" "Multicomp Pro")
    (property "Sheetfile" "sdi-mipi-bridge.kicad_sch")
    (property "Sheetname" "")
    (property "ki_description" "Pin Header, Board-to-Board, 1.27 mm, 2 Rows, 10 Contacts, Through Hole Straight, 2199SB")
    (property "ki_keywords" "PINSTRIP, HEADER, THT")
    (attr through_hole)
    (fp_text reference "J6" (at 0 -2.9 90) (layer "F.SilkS")
        (effects (font (size 0.7 0.7) (thickness 0.15)) (justify left bottom))
    )
    (fp_text value "PinHeader_2x5_P1.27mm_Vertical" (at 0 2.3 90) (layer "F.Fab") hide
        (effects (font (size 0.7 0.7) (thickness 0.15)) (justify left bottom))
    )
    (fp_text user "${REFERENCE}" (at -1.135 9.999 90) (layer "F.Fab") hide
        (effects (font (size 0.7 0.7) (thickness 0.15)) (justify left bottom))
    )
    (fp_text user "License: Apache-2.0" (at -1.135 11.198 90) (layer "F.Fab") hide
        (effects (font (size 0.7 0.7) (thickness 0.15)) (justify left bottom))
    )
    (fp_text user "Author: Antmicro" (at -1.135 12.399 90) (layer "F.Fab") hide
        (effects (font (size 0.7 0.7) (thickness 0.15)) (justify left bottom))
    )
    (fp_line (start -0.702 -2.403) (end -0.702 -1.901)
      (stroke (width 0.15) (type solid)) (layer "F.SilkS"))
    (fp_line (start -0.702 -2.403) (end -0.202 -2.403)
      (stroke (width 0.15) (type solid)) (layer "F.SilkS"))
    (fp_line (start 5.797 -2.4) (end 5.297 -2.4)
      (stroke (width 0.15) (type solid)) (layer "F.SilkS"))
    (fp_line (start 5.797 -2.4) (end 5.797 -1.899)
      (stroke (width 0.15) (type solid)) (layer "F.SilkS"))
    (fp_line (start 5.797 1.1) (end 5.297 1.1)
      (stroke (width 0.15) (type solid)) (layer "F.SilkS"))
    (fp_line (start 5.797 1.1) (end 5.797 0.598)
      (stroke (width 0.15) (type solid)) (layer "F.SilkS"))
    (fp_poly
      (pts
        (xy -0.702 0.598)
        (xy -0.702 1.1)
        (xy -0.202 1.1)
      )

      (stroke (width 0.15) (type solid)) (fill solid) (layer "F.SilkS"))
    (fp_rect (start -0.9 -2.6) (end 6 1.3)
      (stroke (width 0.05) (type solid)) (fill none) (layer "F.CrtYd"))
    (fp_line (start -0.635 -2.339) (end 5.712 -2.339)
      (stroke (width 0.15) (type solid)) (layer "F.Fab"))
    (fp_line (start -0.635 0.216) (end -0.635 -2.339)
      (stroke (width 0.15) (type solid)) (layer "F.Fab"))
    (fp_line (start 0.214 1.07) (end -0.635 0.216)
      (stroke (width 0.15) (type solid)) (layer "F.Fab"))
    (fp_line (start 5.712 -2.339) (end 5.712 1.07)
      (stroke (width 0.15) (type solid)) (layer "F.Fab"))
    (fp_line (start 5.712 1.07) (end 0.214 1.07)
      (stroke (width 0.15) (type solid)) (layer "F.Fab"))
    (pad "1" thru_hole rect (at 0 0 180) (size 1 1) (drill 0.65) (layers "*.Cu" "*.Mask")
      (net 6 "+3V3") (pintype "passive"))
    (pad "2" thru_hole oval (at 0 -1.27 180) (size 1 1) (drill 0.65) (layers "*.Cu" "*.Mask")
      (net 103 "/USER_SDA") (pintype "passive"))
    (pad "3" thru_hole oval (at 1.269 0 180) (size 1 1) (drill 0.65) (layers "*.Cu" "*.Mask")
      (net 102 "/SPI_SCK(SDA)") (pintype "passive"))
    (pad "4" thru_hole oval (at 1.269 -1.27 180) (size 1 1) (drill 0.65) (layers "*.Cu" "*.Mask")
      (net 101 "/USER_SCL") (pintype "passive"))
    (pad "5" thru_hole oval (at 2.539 0 180) (size 1 1) (drill 0.65) (layers "*.Cu" "*.Mask")
      (net 97 "/MOSI") (pintype "passive"))
    (pad "6" thru_hole oval (at 2.539 -1.27 180) (size 1 1) (drill 0.65) (layers "*.Cu" "*.Mask")
      (net 124 "unconnected-(J6-Pad6)") (pintype "passive+no_connect"))
    (pad "7" thru_hole oval (at 3.809 0 180) (size 1 1) (drill 0.65) (layers "*.Cu" "*.Mask")
      (net 96 "/MISO") (pintype "passive"))
    (pad "8" thru_hole oval (at 3.809 -1.27 180) (size 1 1) (drill 0.65) (layers "*.Cu" "*.Mask")
      (net 100 "/CRESET_B") (pintype "passive"))
    (pad "9" thru_hole oval (at 5.076 0 180) (size 1 1) (drill 0.65) (layers "*.Cu" "*.Mask")
      (net 99 "/SPI_SS(SCL)") (pintype "passive"))
    (pad "10" thru_hole oval (at 5.076 -1.27 180) (size 1 1) (drill 0.65) (layers "*.Cu" "*.Mask")
      (net 1 "GNDREF") (pintype "passive"))
  )
)
